;LEADER: 12 
;HEADER: 
;CODE  : ASCII 
;FILE  : 9324_DA0F0TMBIJ0_F0T_Motherboard_J_v01_20230324_0910-bd-1-6.drl for backdrilling ... from layer TOP to layer GND2
;DESIGN: 9324_DA0F0TMBIJ0_F0T_Motherboard_J_v01_20230324_0910.brd
;MUST-NOT-CUT-LAYER = IN3,  MAX_DRILL_DEPTH = 31.20 MILS,  MFG_STUB_LENGTH = 0.00 MILS
;   BackdrillSize 1. = 17.700000 Tolerance = +0.000000/-0.000000 NON_PLATED MILS Quantity = 16
%
G90
X1361771Y0332275
X1351800Y0337843
X1345424Y0328981
X1338031Y0322693
X1331745Y0332616
X1328480Y0323902
X1316218Y0318073
X1311077Y0322996
X1358371Y0332275
X1355200Y0337843
X1348824Y0328981
X1341431Y0322693
X1335145Y0332616
X1325080Y0323902
X1319618Y0318073
X1307677Y0322996
M30
